(kicad_pcb
	(version 20260206)
	(generator "pcbnew")
	(generator_version "10.0")
	(general
		(thickness 1.6)
		(legacy_teardrops no)
	)
	(paper "A4")
	(title_block
		(title "04192023_DAF0TMB3IC0_F0TG_MB_C_brd_V02_OCP.brd")
		(comment 1 "Grand Teton / footprints 1231-1238 of 8354")
	)
	(layers
		(0 "F.Cu" signal "TOP")
		(4 "In1.Cu" signal "GND")
		(6 "In2.Cu" signal "IN1")
		(8 "In3.Cu" signal "GND1")
		(10 "In4.Cu" signal "IN2")
		(12 "In5.Cu" signal "GND2")
		(14 "In6.Cu" signal "IN3")
		(16 "In7.Cu" signal "GND3")
		(18 "In8.Cu" signal "VCC")
		(20 "In9.Cu" signal "VCC1")
		(22 "In10.Cu" signal "GND4")
		(24 "In11.Cu" signal "IN4")
		(26 "In12.Cu" signal "GND5")
		(28 "In13.Cu" signal "IN5")
		(30 "In14.Cu" signal "GND6")
		(32 "In15.Cu" signal "IN6")
		(34 "In16.Cu" signal "GND7")
		(2 "B.Cu" signal "BOTTOM")
		(9 "F.Adhes" user "F.Adhesive")
		(11 "B.Adhes" user "B.Adhesive")
		(13 "F.Paste" user "Package Geometry/Pastemask Top")
		(15 "B.Paste" user "Package Geometry/Pastemask Bottom")
		(5 "F.SilkS" user "Ref Des/Silkscreen Top")
		(7 "B.SilkS" user "Ref Des/Silkscreen Bottom")
		(1 "F.Mask" user "Board Geometry/Soldermask Top")
		(3 "B.Mask" user "Board Geometry/Soldermask Bottom")
		(17 "Dwgs.User" user "User.Drawings")
		(19 "Cmts.User" user "User.Comments")
		(21 "Eco1.User" user "User.Eco1")
		(23 "Eco2.User" user "User.Eco2")
		(25 "Edge.Cuts" user "Board Geometry/Outline")
		(27 "Margin" user)
		(31 "F.CrtYd" user "Package Geometry/Place Bound Top")
		(29 "B.CrtYd" user "Package Geometry/Place Bound Bottom")
		(35 "F.Fab" user "Ref Des/Assembly Top")
		(33 "B.Fab" user "Ref Des/Assembly Bottom")
	)
	(footprint ""
		(layer "F.Cu")
		(at 420.246302 -434.386736 -90)
		(property "Reference" "C4"
			(at 0 0 270)
			(layer "F.SilkS")
			(hide yes)
			(effects
				(font
					(size 1.27 1.27)
				)
			)
		)
		(property "Value" ""
			(at 0 0 270)
			(layer "F.Fab")
			(effects
				(font
					(size 1.27 1.27)
				)
			)
		)
		(duplicate_pad_numbers_are_jumpers no)
		(fp_line
			(start -0.7874 0.4064)
			(end -0.7874 -0.4064)
			(stroke
				(width 0.1524)
				(type default)
			)
			(layer "F.SilkS")
		)
		(fp_line
			(start 0.7874 0.4064)
			(end -0.7874 0.4064)
			(stroke
				(width 0.1524)
				(type default)
			)
			(layer "F.SilkS")
		)
		(fp_line
			(start -0.7874 -0.4064)
			(end 0.7874 -0.4064)
			(stroke
				(width 0.1524)
				(type default)
			)
			(layer "F.SilkS")
		)
		(fp_line
			(start 0.7874 -0.4064)
			(end 0.7874 0.4064)
			(stroke
				(width 0.1524)
				(type default)
			)
			(layer "F.SilkS")
		)
		(fp_line
			(start -0.67945 0.3048)
			(end -0.67945 -0.305054)
			(stroke
				(width 0.1)
				(type default)
			)
			(layer "F.Fab")
		)
		(fp_line
			(start -0.12065 0.3048)
			(end -0.67945 0.3048)
			(stroke
				(width 0.1)
				(type default)
			)
			(layer "F.Fab")
		)
		(fp_line
			(start 0.120396 0.3048)
			(end 0.120396 0.2794)
			(stroke
				(width 0.1)
				(type default)
			)
			(layer "F.Fab")
		)
		(fp_line
			(start 0.67945 0.3048)
			(end 0.120396 0.3048)
			(stroke
				(width 0.1)
				(type default)
			)
			(layer "F.Fab")
		)
		(fp_line
			(start -0.12065 0.2794)
			(end -0.12065 0.3048)
			(stroke
				(width 0.1)
				(type default)
			)
			(layer "F.Fab")
		)
		(fp_line
			(start 0.120396 0.2794)
			(end -0.12065 0.2794)
			(stroke
				(width 0.1)
				(type default)
			)
			(layer "F.Fab")
		)
		(fp_line
			(start -0.12065 -0.2794)
			(end 0.12065 -0.2794)
			(stroke
				(width 0.1)
				(type default)
			)
			(layer "F.Fab")
		)
		(fp_line
			(start 0.12065 -0.2794)
			(end 0.12065 -0.3048)
			(stroke
				(width 0.1)
				(type default)
			)
			(layer "F.Fab")
		)
		(fp_line
			(start 0.12065 -0.3048)
			(end 0.67945 -0.3048)
			(stroke
				(width 0.1)
				(type default)
			)
			(layer "F.Fab")
		)
		(fp_line
			(start 0.67945 -0.3048)
			(end 0.67945 0.3048)
			(stroke
				(width 0.1)
				(type default)
			)
			(layer "F.Fab")
		)
		(fp_line
			(start -0.67945 -0.305054)
			(end -0.12065 -0.305054)
			(stroke
				(width 0.1)
				(type default)
			)
			(layer "F.Fab")
		)
		(fp_line
			(start -0.12065 -0.305054)
			(end -0.12065 -0.2794)
			(stroke
				(width 0.1)
				(type default)
			)
			(layer "F.Fab")
		)
		(pad "1" smd circle
			(at -0.40005 0 270)
			(size 0 0)
			(layers "F.Cu" "F.Mask" "F.Paste")
			(net "GPU_3V3IO_RSVD1_ISO")
		)
		(pad "2" smd circle
			(at 0.40005 0 270)
			(size 0 0)
			(layers "F.Cu" "F.Mask" "F.Paste")
			(net "GND")
		)
	)
	(footprint ""
		(layer "F.Cu")
		(at 120.340882 -14.00429)
		(property "Reference" "R4185"
			(at 0 0 0)
			(layer "F.SilkS")
			(hide yes)
			(effects
				(font
					(size 1.27 1.27)
				)
			)
		)
		(property "Value" ""
			(at 0 0 0)
			(layer "F.Fab")
			(effects
				(font
					(size 1.27 1.27)
				)
			)
		)
		(duplicate_pad_numbers_are_jumpers no)
		(fp_line
			(start -0.7874 -0.4064)
			(end 0.7874 -0.4064)
			(stroke
				(width 0.1524)
				(type default)
			)
			(layer "F.SilkS")
		)
		(fp_line
			(start -0.7874 0.4064)
			(end -0.7874 -0.4064)
			(stroke
				(width 0.1524)
				(type default)
			)
			(layer "F.SilkS")
		)
		(fp_line
			(start 0.7874 -0.4064)
			(end 0.7874 0.4064)
			(stroke
				(width 0.1524)
				(type default)
			)
			(layer "F.SilkS")
		)
		(fp_line
			(start 0.7874 0.4064)
			(end -0.7874 0.4064)
			(stroke
				(width 0.1524)
				(type default)
			)
			(layer "F.SilkS")
		)
		(fp_line
			(start -0.67945 -0.305054)
			(end -0.12065 -0.305054)
			(stroke
				(width 0.1)
				(type default)
			)
			(layer "F.Fab")
		)
		(fp_line
			(start -0.67945 0.3048)
			(end -0.67945 -0.305054)
			(stroke
				(width 0.1)
				(type default)
			)
			(layer "F.Fab")
		)
		(fp_line
			(start -0.12065 -0.305054)
			(end -0.12065 -0.2794)
			(stroke
				(width 0.1)
				(type default)
			)
			(layer "F.Fab")
		)
		(fp_line
			(start -0.12065 -0.2794)
			(end 0.12065 -0.2794)
			(stroke
				(width 0.1)
				(type default)
			)
			(layer "F.Fab")
		)
		(fp_line
			(start -0.12065 0.2794)
			(end -0.12065 0.3048)
			(stroke
				(width 0.1)
				(type default)
			)
			(layer "F.Fab")
		)
		(fp_line
			(start -0.12065 0.3048)
			(end -0.67945 0.3048)
			(stroke
				(width 0.1)
				(type default)
			)
			(layer "F.Fab")
		)
		(fp_line
			(start 0.120396 0.2794)
			(end -0.12065 0.2794)
			(stroke
				(width 0.1)
				(type default)
			)
			(layer "F.Fab")
		)
		(fp_line
			(start 0.120396 0.3048)
			(end 0.120396 0.2794)
			(stroke
				(width 0.1)
				(type default)
			)
			(layer "F.Fab")
		)
		(fp_line
			(start 0.12065 -0.3048)
			(end 0.67945 -0.3048)
			(stroke
				(width 0.1)
				(type default)
			)
			(layer "F.Fab")
		)
		(fp_line
			(start 0.12065 -0.2794)
			(end 0.12065 -0.3048)
			(stroke
				(width 0.1)
				(type default)
			)
			(layer "F.Fab")
		)
		(fp_line
			(start 0.67945 -0.3048)
			(end 0.67945 0.3048)
			(stroke
				(width 0.1)
				(type default)
			)
			(layer "F.Fab")
		)
		(fp_line
			(start 0.67945 0.3048)
			(end 0.120396 0.3048)
			(stroke
				(width 0.1)
				(type default)
			)
			(layer "F.Fab")
		)
		(pad "1" smd circle
			(at -0.40005 0)
			(size 0 0)
			(layers "F.Cu" "F.Mask" "F.Paste")
			(net "U273_3_ADD2")
		)
		(pad "2" smd circle
			(at 0.40005 0)
			(size 0 0)
			(layers "F.Cu" "F.Mask" "F.Paste")
			(net "GND")
		)
	)
	(footprint ""
		(layer "F.Cu")
		(at 31.726378 -401.398232)
		(property "Reference" "PC473"
			(at -1.627378 -3.578098 0)
			(unlocked yes)
			(layer "F.SilkS")
			(effects
				(font
					(size 0.7874 0.5842)
					(thickness 0.1524)
				)
				(justify left)
			)
		)
		(property "Value" ""
			(at 0 0 0)
			(layer "F.Fab")
			(effects
				(font
					(size 1.27 1.27)
				)
			)
		)
		(duplicate_pad_numbers_are_jumpers no)
		(fp_line
			(start -2.750058 -1.988058)
			(end -2.750058 -0.9398)
			(stroke
				(width 0.1524)
				(type default)
			)
			(layer "F.SilkS")
		)
		(fp_line
			(start -2.750058 0.9398)
			(end -2.750058 1.988058)
			(stroke
				(width 0.1524)
				(type default)
			)
			(layer "F.SilkS")
		)
		(fp_line
			(start -2.750058 1.988058)
			(end -1.988058 2.750058)
			(stroke
				(width 0.1524)
				(type default)
			)
			(layer "F.SilkS")
		)
		(fp_line
			(start -1.988058 -2.750058)
			(end -2.750058 -1.988058)
			(stroke
				(width 0.1524)
				(type default)
			)
			(layer "F.SilkS")
		)
		(fp_line
			(start -1.988058 2.750058)
			(end 2.750058 2.750058)
			(stroke
				(width 0.1524)
				(type default)
			)
			(layer "F.SilkS")
		)
		(fp_line
			(start 2.750058 -2.750058)
			(end -1.988058 -2.750058)
			(stroke
				(width 0.1524)
				(type default)
			)
			(layer "F.SilkS")
		)
		(fp_line
			(start 2.750058 -0.9398)
			(end 2.750058 -2.750058)
			(stroke
				(width 0.1524)
				(type default)
			)
			(layer "F.SilkS")
		)
		(fp_line
			(start 2.750058 2.750058)
			(end 2.750058 0.9398)
			(stroke
				(width 0.1524)
				(type default)
			)
			(layer "F.SilkS")
		)
		(fp_line
			(start -2.750058 -2.750058)
			(end -2.750058 2.750058)
			(stroke
				(width 0.1)
				(type default)
			)
			(layer "F.Fab")
		)
		(fp_line
			(start -2.750058 2.750058)
			(end 2.750058 2.750058)
			(stroke
				(width 0.1)
				(type default)
			)
			(layer "F.Fab")
		)
		(fp_line
			(start 2.750058 -2.750058)
			(end -2.750058 -2.750058)
			(stroke
				(width 0.1)
				(type default)
			)
			(layer "F.Fab")
		)
		(fp_line
			(start 2.750058 2.750058)
			(end 2.750058 -2.750058)
			(stroke
				(width 0.1)
				(type default)
			)
			(layer "F.Fab")
		)
		(pad "1" smd rect
			(at -2.199894 0 90)
			(size 1.6002 3.0226)
			(layers "F.Cu" "F.Mask" "F.Paste")
			(net "SW_P12V_AUX_P0V9_RETIMER_CPU1_FLT")
		)
		(pad "2" smd rect
			(at 2.199894 0 90)
			(size 1.6002 3.0226)
			(layers "F.Cu" "F.Mask" "F.Paste")
			(net "GND")
		)
	)
	(footprint ""
		(layer "F.Cu")
		(at 420.246302 -440.012836 -90)
		(property "Reference" "R2828"
			(at 0 0 270)
			(layer "F.SilkS")
			(hide yes)
			(effects
				(font
					(size 1.27 1.27)
				)
			)
		)
		(property "Value" ""
			(at 0 0 270)
			(layer "F.Fab")
			(effects
				(font
					(size 1.27 1.27)
				)
			)
		)
		(duplicate_pad_numbers_are_jumpers no)
		(fp_line
			(start -0.7874 0.4064)
			(end -0.7874 -0.4064)
			(stroke
				(width 0.1524)
				(type default)
			)
			(layer "F.SilkS")
		)
		(fp_line
			(start 0.7874 0.4064)
			(end -0.7874 0.4064)
			(stroke
				(width 0.1524)
				(type default)
			)
			(layer "F.SilkS")
		)
		(fp_line
			(start -0.7874 -0.4064)
			(end 0.7874 -0.4064)
			(stroke
				(width 0.1524)
				(type default)
			)
			(layer "F.SilkS")
		)
		(fp_line
			(start 0.7874 -0.4064)
			(end 0.7874 0.4064)
			(stroke
				(width 0.1524)
				(type default)
			)
			(layer "F.SilkS")
		)
		(fp_line
			(start -0.67945 0.3048)
			(end -0.67945 -0.305054)
			(stroke
				(width 0.1)
				(type default)
			)
			(layer "F.Fab")
		)
		(fp_line
			(start -0.12065 0.3048)
			(end -0.67945 0.3048)
			(stroke
				(width 0.1)
				(type default)
			)
			(layer "F.Fab")
		)
		(fp_line
			(start 0.120396 0.3048)
			(end 0.120396 0.2794)
			(stroke
				(width 0.1)
				(type default)
			)
			(layer "F.Fab")
		)
		(fp_line
			(start 0.67945 0.3048)
			(end 0.120396 0.3048)
			(stroke
				(width 0.1)
				(type default)
			)
			(layer "F.Fab")
		)
		(fp_line
			(start -0.12065 0.2794)
			(end -0.12065 0.3048)
			(stroke
				(width 0.1)
				(type default)
			)
			(layer "F.Fab")
		)
		(fp_line
			(start 0.120396 0.2794)
			(end -0.12065 0.2794)
			(stroke
				(width 0.1)
				(type default)
			)
			(layer "F.Fab")
		)
		(fp_line
			(start -0.12065 -0.2794)
			(end 0.12065 -0.2794)
			(stroke
				(width 0.1)
				(type default)
			)
			(layer "F.Fab")
		)
		(fp_line
			(start 0.12065 -0.2794)
			(end 0.12065 -0.3048)
			(stroke
				(width 0.1)
				(type default)
			)
			(layer "F.Fab")
		)
		(fp_line
			(start 0.12065 -0.3048)
			(end 0.67945 -0.3048)
			(stroke
				(width 0.1)
				(type default)
			)
			(layer "F.Fab")
		)
		(fp_line
			(start 0.67945 -0.3048)
			(end 0.67945 0.3048)
			(stroke
				(width 0.1)
				(type default)
			)
			(layer "F.Fab")
		)
		(fp_line
			(start -0.67945 -0.305054)
			(end -0.12065 -0.305054)
			(stroke
				(width 0.1)
				(type default)
			)
			(layer "F.Fab")
		)
		(fp_line
			(start -0.12065 -0.305054)
			(end -0.12065 -0.2794)
			(stroke
				(width 0.1)
				(type default)
			)
			(layer "F.Fab")
		)
		(pad "1" smd circle
			(at -0.40005 0 270)
			(size 0 0)
			(layers "F.Cu" "F.Mask" "F.Paste")
			(net "P3V3_AUX")
		)
		(pad "2" smd circle
			(at 0.40005 0 270)
			(size 0 0)
			(layers "F.Cu" "F.Mask" "F.Paste")
			(net "RST_BMC_FROM_SWB_N")
		)
	)
	(footprint ""
		(layer "F.Cu")
		(at 392.081258 -402.9202 -90)
		(property "Reference" "R1126"
			(at 0 0 270)
			(layer "F.SilkS")
			(hide yes)
			(effects
				(font
					(size 1.27 1.27)
				)
			)
		)
		(property "Value" ""
			(at 0 0 270)
			(layer "F.Fab")
			(effects
				(font
					(size 1.27 1.27)
				)
			)
		)
		(duplicate_pad_numbers_are_jumpers no)
		(fp_line
			(start -0.32512 0.175006)
			(end -0.32512 -0.175006)
			(stroke
				(width 0.1)
				(type default)
			)
			(layer "F.Fab")
		)
		(fp_line
			(start 0.32512 0.175006)
			(end -0.32512 0.175006)
			(stroke
				(width 0.1)
				(type default)
			)
			(layer "F.Fab")
		)
		(fp_line
			(start -0.32512 -0.175006)
			(end 0.32512 -0.175006)
			(stroke
				(width 0.1)
				(type default)
			)
			(layer "F.Fab")
		)
		(fp_line
			(start 0.32512 -0.175006)
			(end 0.32512 0.175006)
			(stroke
				(width 0.1)
				(type default)
			)
			(layer "F.Fab")
		)
		(pad "1" smd rect
			(at -0.2667 0 270)
			(size 0.3048 0.381)
			(layers "F.Cu" "F.Mask" "F.Paste")
			(net "NCF_A1_CPU0_P3_GND")
		)
		(pad "2" smd rect
			(at 0.2667 0 90)
			(size 0.3048 0.381)
			(layers "F.Cu" "F.Mask" "F.Paste")
			(net "GND")
		)
	)
	(footprint ""
		(layer "F.Cu")
		(at 290.311586 -398.613376 90)
		(property "Reference" "R678"
			(at 0 0 90)
			(layer "F.SilkS")
			(hide yes)
			(effects
				(font
					(size 1.27 1.27)
				)
			)
		)
		(property "Value" ""
			(at 0 0 90)
			(layer "F.Fab")
			(effects
				(font
					(size 1.27 1.27)
				)
			)
		)
		(duplicate_pad_numbers_are_jumpers no)
		(fp_line
			(start 0.32512 -0.175006)
			(end 0.32512 0.175006)
			(stroke
				(width 0.1)
				(type default)
			)
			(layer "F.Fab")
		)
		(fp_line
			(start -0.32512 -0.175006)
			(end 0.32512 -0.175006)
			(stroke
				(width 0.1)
				(type default)
			)
			(layer "F.Fab")
		)
		(fp_line
			(start 0.32512 0.175006)
			(end -0.32512 0.175006)
			(stroke
				(width 0.1)
				(type default)
			)
			(layer "F.Fab")
		)
		(fp_line
			(start -0.32512 0.175006)
			(end -0.32512 -0.175006)
			(stroke
				(width 0.1)
				(type default)
			)
			(layer "F.Fab")
		)
		(pad "1" smd rect
			(at -0.2667 0 90)
			(size 0.3048 0.381)
			(layers "F.Cu" "F.Mask" "F.Paste")
			(net "SMB_RT_CPU0_P1_ROM_R_SCL")
		)
		(pad "2" smd rect
			(at 0.2667 0 270)
			(size 0.3048 0.381)
			(layers "F.Cu" "F.Mask" "F.Paste")
			(net "SMB_RT_CPU0_P1_ROM_SCL")
		)
	)
	(footprint ""
		(layer "F.Cu")
		(at 110.644432 -397.232378 180)
		(property "Reference" "C7502"
			(at 0 0 180)
			(layer "F.SilkS")
			(hide yes)
			(effects
				(font
					(size 1.27 1.27)
				)
			)
		)
		(property "Value" ""
			(at 0 0 180)
			(layer "F.Fab")
			(effects
				(font
					(size 1.27 1.27)
				)
			)
		)
		(duplicate_pad_numbers_are_jumpers no)
		(fp_line
			(start 0.299974 0.150114)
			(end -0.299974 0.150114)
			(stroke
				(width 0.1)
				(type default)
			)
			(layer "F.Fab")
		)
		(fp_line
			(start 0.299974 -0.150114)
			(end 0.299974 0.150114)
			(stroke
				(width 0.1)
				(type default)
			)
			(layer "F.Fab")
		)
		(fp_line
			(start -0.299974 0.150114)
			(end -0.299974 -0.150114)
			(stroke
				(width 0.1)
				(type default)
			)
			(layer "F.Fab")
		)
		(fp_line
			(start -0.299974 -0.150114)
			(end 0.299974 -0.150114)
			(stroke
				(width 0.1)
				(type default)
			)
			(layer "F.Fab")
		)
		(pad "1" smd rect
			(at -0.2667 0 180)
			(size 0.3048 0.381)
			(layers "F.Cu" "F.Mask" "F.Paste")
			(net "P1V8_CPU1_RT_1D")
		)
		(pad "2" smd rect
			(at 0.2667 0 180)
			(size 0.3048 0.381)
			(layers "F.Cu" "F.Mask" "F.Paste")
			(net "GND")
		)
	)
	(footprint ""
		(layer "F.Cu")
		(at 140.886942 -102.510844 180)
		(property "Reference" "R2113"
			(at 0 0 180)
			(layer "F.SilkS")
			(hide yes)
			(effects
				(font
					(size 1.27 1.27)
				)
			)
		)
		(property "Value" ""
			(at 0 0 180)
			(layer "F.Fab")
			(effects
				(font
					(size 1.27 1.27)
				)
			)
		)
		(duplicate_pad_numbers_are_jumpers no)
		(fp_line
			(start 0.7874 0.4064)
			(end -0.7874 0.4064)
			(stroke
				(width 0.1524)
				(type default)
			)
			(layer "F.SilkS")
		)
		(fp_line
			(start 0.7874 -0.4064)
			(end 0.7874 0.4064)
			(stroke
				(width 0.1524)
				(type default)
			)
			(layer "F.SilkS")
		)
		(fp_line
			(start -0.7874 0.4064)
			(end -0.7874 -0.4064)
			(stroke
				(width 0.1524)
				(type default)
			)
			(layer "F.SilkS")
		)
		(fp_line
			(start -0.7874 -0.4064)
			(end 0.7874 -0.4064)
			(stroke
				(width 0.1524)
				(type default)
			)
			(layer "F.SilkS")
		)
		(fp_line
			(start 0.67945 0.3048)
			(end 0.120396 0.3048)
			(stroke
				(width 0.1)
				(type default)
			)
			(layer "F.Fab")
		)
		(fp_line
			(start 0.67945 -0.3048)
			(end 0.67945 0.3048)
			(stroke
				(width 0.1)
				(type default)
			)
			(layer "F.Fab")
		)
		(fp_line
			(start 0.12065 -0.2794)
			(end 0.12065 -0.3048)
			(stroke
				(width 0.1)
				(type default)
			)
			(layer "F.Fab")
		)
		(fp_line
			(start 0.12065 -0.3048)
			(end 0.67945 -0.3048)
			(stroke
				(width 0.1)
				(type default)
			)
			(layer "F.Fab")
		)
		(fp_line
			(start 0.120396 0.3048)
			(end 0.120396 0.2794)
			(stroke
				(width 0.1)
				(type default)
			)
			(layer "F.Fab")
		)
		(fp_line
			(start 0.120396 0.2794)
			(end -0.12065 0.2794)
			(stroke
				(width 0.1)
				(type default)
			)
			(layer "F.Fab")
		)
		(fp_line
			(start -0.12065 0.3048)
			(end -0.67945 0.3048)
			(stroke
				(width 0.1)
				(type default)
			)
			(layer "F.Fab")
		)
		(fp_line
			(start -0.12065 0.2794)
			(end -0.12065 0.3048)
			(stroke
				(width 0.1)
				(type default)
			)
			(layer "F.Fab")
		)
		(fp_line
			(start -0.12065 -0.2794)
			(end 0.12065 -0.2794)
			(stroke
				(width 0.1)
				(type default)
			)
			(layer "F.Fab")
		)
		(fp_line
			(start -0.12065 -0.305054)
			(end -0.12065 -0.2794)
			(stroke
				(width 0.1)
				(type default)
			)
			(layer "F.Fab")
		)
		(fp_line
			(start -0.67945 0.3048)
			(end -0.67945 -0.305054)
			(stroke
				(width 0.1)
				(type default)
			)
			(layer "F.Fab")
		)
		(fp_line
			(start -0.67945 -0.305054)
			(end -0.12065 -0.305054)
			(stroke
				(width 0.1)
				(type default)
			)
			(layer "F.Fab")
		)
		(pad "1" smd circle
			(at -0.40005 0 180)
			(size 0 0)
			(layers "F.Cu" "F.Mask" "F.Paste")
			(net "RST_PERST_BUF_M2_0_N")
		)
		(pad "2" smd circle
			(at 0.40005 0 180)
			(size 0 0)
			(layers "F.Cu" "F.Mask" "F.Paste")
			(net "RST_PERST_BUF_M2_0_R_N")
		)
	)
)
